(kicad_pcb
	(version 20260206)
	(generator "pcbnew")
	(generator_version "10.0")
	(general
		(thickness 1.6)
		(legacy_teardrops no)
	)
	(paper "A4")
	(title_block
		(title "03242023_DA0F0TMBIJ0_F0T_Motherboard_J_brd_V01_OCP.brd")
		(comment 1 "Grand Teton / footprints 4655-4661 of 6105")
	)
	(layers
		(0 "F.Cu" signal "TOP")
		(4 "In1.Cu" signal "GND")
		(6 "In2.Cu" signal "IN1")
		(8 "In3.Cu" signal "GND1")
		(10 "In4.Cu" signal "IN2")
		(12 "In5.Cu" signal "GND2")
		(14 "In6.Cu" signal "IN3")
		(16 "In7.Cu" signal "GND3")
		(18 "In8.Cu" signal "VCC")
		(20 "In9.Cu" signal "VCC1")
		(22 "In10.Cu" signal "GND4")
		(24 "In11.Cu" signal "IN4")
		(26 "In12.Cu" signal "GND5")
		(28 "In13.Cu" signal "IN5")
		(30 "In14.Cu" signal "GND6")
		(32 "In15.Cu" signal "IN6")
		(34 "In16.Cu" signal "GND7")
		(2 "B.Cu" signal "BOTTOM")
		(9 "F.Adhes" user "F.Adhesive")
		(11 "B.Adhes" user "B.Adhesive")
		(13 "F.Paste" user "Package Geometry/Pastemask Top")
		(15 "B.Paste" user "Package Geometry/Pastemask Bottom")
		(5 "F.SilkS" user "Ref Des/Silkscreen Top")
		(7 "B.SilkS" user "Ref Des/Silkscreen Bottom")
		(1 "F.Mask" user "Board Geometry/Soldermask Top")
		(3 "B.Mask" user "Board Geometry/Soldermask Bottom")
		(17 "Dwgs.User" user "User.Drawings")
		(19 "Cmts.User" user "User.Comments")
		(21 "Eco1.User" user "User.Eco1")
		(23 "Eco2.User" user "User.Eco2")
		(25 "Edge.Cuts" user "Board Geometry/Outline")
		(27 "Margin" user)
		(31 "F.CrtYd" user "Package Geometry/Place Bound Top")
		(29 "B.CrtYd" user "Package Geometry/Place Bound Bottom")
		(35 "F.Fab" user "Ref Des/Assembly Top")
		(33 "B.Fab" user "Ref Des/Assembly Bottom")
	)
	(footprint ""
		(layer "B.Cu")
		(at 321.039998 -188.96711 -90)
		(property "Reference" "R277"
			(at 0 0 90)
			(layer "B.SilkS")
			(hide yes)
			(effects
				(font
					(size 1.27 1.27)
				)
				(justify mirror)
			)
		)
		(property "Value" ""
			(at 0 0 90)
			(layer "B.Fab")
			(effects
				(font
					(size 1.27 1.27)
				)
				(justify mirror)
			)
		)
		(duplicate_pad_numbers_are_jumpers no)
		(fp_line
			(start -0.7874 0.4064)
			(end 0.7874 0.4064)
			(stroke
				(width 0.1524)
				(type default)
			)
			(layer "B.SilkS")
		)
		(fp_line
			(start 0.7874 0.4064)
			(end 0.7874 -0.4064)
			(stroke
				(width 0.1524)
				(type default)
			)
			(layer "B.SilkS")
		)
		(fp_line
			(start -0.7874 -0.4064)
			(end -0.7874 0.4064)
			(stroke
				(width 0.1524)
				(type default)
			)
			(layer "B.SilkS")
		)
		(fp_line
			(start 0.7874 -0.4064)
			(end -0.7874 -0.4064)
			(stroke
				(width 0.1524)
				(type default)
			)
			(layer "B.SilkS")
		)
		(fp_line
			(start -0.67945 0.3048)
			(end -0.120396 0.3048)
			(stroke
				(width 0.1)
				(type default)
			)
			(layer "B.Fab")
		)
		(fp_line
			(start -0.120396 0.3048)
			(end -0.120396 0.2794)
			(stroke
				(width 0.1)
				(type default)
			)
			(layer "B.Fab")
		)
		(fp_line
			(start 0.12065 0.3048)
			(end 0.67945 0.3048)
			(stroke
				(width 0.1)
				(type default)
			)
			(layer "B.Fab")
		)
		(fp_line
			(start 0.67945 0.3048)
			(end 0.67945 -0.305054)
			(stroke
				(width 0.1)
				(type default)
			)
			(layer "B.Fab")
		)
		(fp_line
			(start -0.120396 0.2794)
			(end 0.12065 0.2794)
			(stroke
				(width 0.1)
				(type default)
			)
			(layer "B.Fab")
		)
		(fp_line
			(start 0.12065 0.2794)
			(end 0.12065 0.3048)
			(stroke
				(width 0.1)
				(type default)
			)
			(layer "B.Fab")
		)
		(fp_line
			(start -0.12065 -0.2794)
			(end -0.12065 -0.3048)
			(stroke
				(width 0.1)
				(type default)
			)
			(layer "B.Fab")
		)
		(fp_line
			(start 0.12065 -0.2794)
			(end -0.12065 -0.2794)
			(stroke
				(width 0.1)
				(type default)
			)
			(layer "B.Fab")
		)
		(fp_line
			(start -0.67945 -0.3048)
			(end -0.67945 0.3048)
			(stroke
				(width 0.1)
				(type default)
			)
			(layer "B.Fab")
		)
		(fp_line
			(start -0.12065 -0.3048)
			(end -0.67945 -0.3048)
			(stroke
				(width 0.1)
				(type default)
			)
			(layer "B.Fab")
		)
		(fp_line
			(start 0.12065 -0.305054)
			(end 0.12065 -0.2794)
			(stroke
				(width 0.1)
				(type default)
			)
			(layer "B.Fab")
		)
		(fp_line
			(start 0.67945 -0.305054)
			(end 0.12065 -0.305054)
			(stroke
				(width 0.1)
				(type default)
			)
			(layer "B.Fab")
		)
		(pad "1" smd circle
			(at 0.40005 0 90)
			(size 0 0)
			(layers "B.Cu" "B.Mask" "B.Paste")
			(net "PVNN_TERM_CPU0")
		)
		(pad "2" smd circle
			(at -0.40005 0 90)
			(size 0 0)
			(layers "B.Cu" "B.Mask" "B.Paste")
			(net "PU_CPU0_FRMAGENT")
		)
	)
	(footprint ""
		(layer "B.Cu")
		(at 376.694446 -78.551278 180)
		(property "Reference" "PR1653"
			(at 0 0 0)
			(layer "B.SilkS")
			(hide yes)
			(effects
				(font
					(size 1.27 1.27)
				)
				(justify mirror)
			)
		)
		(property "Value" ""
			(at 0 0 0)
			(layer "B.Fab")
			(effects
				(font
					(size 1.27 1.27)
				)
				(justify mirror)
			)
		)
		(duplicate_pad_numbers_are_jumpers no)
		(fp_line
			(start 0.7874 0.4064)
			(end 0.7874 -0.4064)
			(stroke
				(width 0.1524)
				(type default)
			)
			(layer "B.SilkS")
		)
		(fp_line
			(start 0.7874 -0.4064)
			(end -0.7874 -0.4064)
			(stroke
				(width 0.1524)
				(type default)
			)
			(layer "B.SilkS")
		)
		(fp_line
			(start -0.7874 0.4064)
			(end 0.7874 0.4064)
			(stroke
				(width 0.1524)
				(type default)
			)
			(layer "B.SilkS")
		)
		(fp_line
			(start -0.7874 -0.4064)
			(end -0.7874 0.4064)
			(stroke
				(width 0.1524)
				(type default)
			)
			(layer "B.SilkS")
		)
		(fp_line
			(start 0.67945 0.3048)
			(end 0.67945 -0.305054)
			(stroke
				(width 0.1)
				(type default)
			)
			(layer "B.Fab")
		)
		(fp_line
			(start 0.67945 -0.305054)
			(end 0.12065 -0.305054)
			(stroke
				(width 0.1)
				(type default)
			)
			(layer "B.Fab")
		)
		(fp_line
			(start 0.12065 0.3048)
			(end 0.67945 0.3048)
			(stroke
				(width 0.1)
				(type default)
			)
			(layer "B.Fab")
		)
		(fp_line
			(start 0.12065 0.2794)
			(end 0.12065 0.3048)
			(stroke
				(width 0.1)
				(type default)
			)
			(layer "B.Fab")
		)
		(fp_line
			(start 0.12065 -0.2794)
			(end -0.12065 -0.2794)
			(stroke
				(width 0.1)
				(type default)
			)
			(layer "B.Fab")
		)
		(fp_line
			(start 0.12065 -0.305054)
			(end 0.12065 -0.2794)
			(stroke
				(width 0.1)
				(type default)
			)
			(layer "B.Fab")
		)
		(fp_line
			(start -0.120396 0.3048)
			(end -0.120396 0.2794)
			(stroke
				(width 0.1)
				(type default)
			)
			(layer "B.Fab")
		)
		(fp_line
			(start -0.120396 0.2794)
			(end 0.12065 0.2794)
			(stroke
				(width 0.1)
				(type default)
			)
			(layer "B.Fab")
		)
		(fp_line
			(start -0.12065 -0.2794)
			(end -0.12065 -0.3048)
			(stroke
				(width 0.1)
				(type default)
			)
			(layer "B.Fab")
		)
		(fp_line
			(start -0.12065 -0.3048)
			(end -0.67945 -0.3048)
			(stroke
				(width 0.1)
				(type default)
			)
			(layer "B.Fab")
		)
		(fp_line
			(start -0.67945 0.3048)
			(end -0.120396 0.3048)
			(stroke
				(width 0.1)
				(type default)
			)
			(layer "B.Fab")
		)
		(fp_line
			(start -0.67945 -0.3048)
			(end -0.67945 0.3048)
			(stroke
				(width 0.1)
				(type default)
			)
			(layer "B.Fab")
		)
		(pad "1" smd circle
			(at 0.40005 0)
			(size 0 0)
			(layers "B.Cu" "B.Mask" "B.Paste")
			(net "P1V8_PCH_AUX")
		)
		(pad "2" smd circle
			(at -0.40005 0)
			(size 0 0)
			(layers "B.Cu" "B.Mask" "B.Paste")
			(net "GND")
		)
	)
	(footprint ""
		(layer "B.Cu")
		(at 252.222 -98.389948 180)
		(property "Reference" "C1311"
			(at 0 0 0)
			(layer "B.SilkS")
			(hide yes)
			(effects
				(font
					(size 1.27 1.27)
				)
				(justify mirror)
			)
		)
		(property "Value" ""
			(at 0 0 0)
			(layer "B.Fab")
			(effects
				(font
					(size 1.27 1.27)
				)
				(justify mirror)
			)
		)
		(duplicate_pad_numbers_are_jumpers no)
		(fp_line
			(start 0.7874 0.4064)
			(end 0.7874 -0.4064)
			(stroke
				(width 0.1524)
				(type default)
			)
			(layer "B.SilkS")
		)
		(fp_line
			(start 0.7874 -0.4064)
			(end -0.7874 -0.4064)
			(stroke
				(width 0.1524)
				(type default)
			)
			(layer "B.SilkS")
		)
		(fp_line
			(start -0.7874 0.4064)
			(end 0.7874 0.4064)
			(stroke
				(width 0.1524)
				(type default)
			)
			(layer "B.SilkS")
		)
		(fp_line
			(start -0.7874 -0.4064)
			(end -0.7874 0.4064)
			(stroke
				(width 0.1524)
				(type default)
			)
			(layer "B.SilkS")
		)
		(fp_line
			(start 0.67945 0.3048)
			(end 0.67945 -0.305054)
			(stroke
				(width 0.1)
				(type default)
			)
			(layer "B.Fab")
		)
		(fp_line
			(start 0.67945 -0.305054)
			(end 0.12065 -0.305054)
			(stroke
				(width 0.1)
				(type default)
			)
			(layer "B.Fab")
		)
		(fp_line
			(start 0.12065 0.3048)
			(end 0.67945 0.3048)
			(stroke
				(width 0.1)
				(type default)
			)
			(layer "B.Fab")
		)
		(fp_line
			(start 0.12065 0.2794)
			(end 0.12065 0.3048)
			(stroke
				(width 0.1)
				(type default)
			)
			(layer "B.Fab")
		)
		(fp_line
			(start 0.12065 -0.2794)
			(end -0.12065 -0.2794)
			(stroke
				(width 0.1)
				(type default)
			)
			(layer "B.Fab")
		)
		(fp_line
			(start 0.12065 -0.305054)
			(end 0.12065 -0.2794)
			(stroke
				(width 0.1)
				(type default)
			)
			(layer "B.Fab")
		)
		(fp_line
			(start -0.120396 0.3048)
			(end -0.120396 0.2794)
			(stroke
				(width 0.1)
				(type default)
			)
			(layer "B.Fab")
		)
		(fp_line
			(start -0.120396 0.2794)
			(end 0.12065 0.2794)
			(stroke
				(width 0.1)
				(type default)
			)
			(layer "B.Fab")
		)
		(fp_line
			(start -0.12065 -0.2794)
			(end -0.12065 -0.3048)
			(stroke
				(width 0.1)
				(type default)
			)
			(layer "B.Fab")
		)
		(fp_line
			(start -0.12065 -0.3048)
			(end -0.67945 -0.3048)
			(stroke
				(width 0.1)
				(type default)
			)
			(layer "B.Fab")
		)
		(fp_line
			(start -0.67945 0.3048)
			(end -0.120396 0.3048)
			(stroke
				(width 0.1)
				(type default)
			)
			(layer "B.Fab")
		)
		(fp_line
			(start -0.67945 -0.3048)
			(end -0.67945 0.3048)
			(stroke
				(width 0.1)
				(type default)
			)
			(layer "B.Fab")
		)
		(pad "1" smd circle
			(at 0.40005 0)
			(size 0 0)
			(layers "B.Cu" "B.Mask" "B.Paste")
			(net "P3V3_AUX_CLK_GEN_VDDXTAL_CK440")
		)
		(pad "2" smd circle
			(at -0.40005 0)
			(size 0 0)
			(layers "B.Cu" "B.Mask" "B.Paste")
			(net "GND")
		)
	)
	(footprint ""
		(layer "B.Cu")
		(at 370.540788 -333.73568 90)
		(property "Reference" "PC284_P0_4"
			(at 0 0 90)
			(layer "B.SilkS")
			(hide yes)
			(effects
				(font
					(size 1.27 1.27)
				)
				(justify mirror)
			)
		)
		(property "Value" ""
			(at 0 0 90)
			(layer "B.Fab")
			(effects
				(font
					(size 1.27 1.27)
				)
				(justify mirror)
			)
		)
		(duplicate_pad_numbers_are_jumpers no)
		(fp_line
			(start 1.524 -0.762)
			(end -1.524 -0.762)
			(stroke
				(width 0.1524)
				(type default)
			)
			(layer "B.SilkS")
		)
		(fp_line
			(start -1.524 -0.762)
			(end -1.524 0.762)
			(stroke
				(width 0.1524)
				(type default)
			)
			(layer "B.SilkS")
		)
		(fp_line
			(start 1.524 0.762)
			(end 1.524 -0.762)
			(stroke
				(width 0.1524)
				(type default)
			)
			(layer "B.SilkS")
		)
		(fp_line
			(start -1.524 0.762)
			(end 1.524 0.762)
			(stroke
				(width 0.1524)
				(type default)
			)
			(layer "B.SilkS")
		)
		(fp_line
			(start 1.1049 -0.724916)
			(end 1.1049 0.724916)
			(stroke
				(width 0.1)
				(type default)
			)
			(layer "B.Fab")
		)
		(fp_line
			(start -1.1049 -0.724916)
			(end 1.1049 -0.724916)
			(stroke
				(width 0.1)
				(type default)
			)
			(layer "B.Fab")
		)
		(fp_line
			(start 1.1049 0.724916)
			(end -1.1049 0.724916)
			(stroke
				(width 0.1)
				(type default)
			)
			(layer "B.Fab")
		)
		(fp_line
			(start -1.1049 0.724916)
			(end -1.1049 -0.724916)
			(stroke
				(width 0.1)
				(type default)
			)
			(layer "B.Fab")
		)
		(pad "1" smd rect
			(at 0.889 0 90)
			(size 1.016 1.27)
			(layers "B.Cu" "B.Mask" "B.Paste")
			(net "SW_P12V_PVCCIN_CPU0_FLT")
		)
		(pad "2" smd rect
			(at -0.889 0 90)
			(size 1.016 1.27)
			(layers "B.Cu" "B.Mask" "B.Paste")
			(net "GND")
		)
	)
	(footprint ""
		(layer "B.Cu")
		(at 324.067424 -343.927938 90)
		(property "Reference" "PR403"
			(at 0 0 90)
			(layer "B.SilkS")
			(hide yes)
			(effects
				(font
					(size 1.27 1.27)
				)
				(justify mirror)
			)
		)
		(property "Value" ""
			(at 0 0 90)
			(layer "B.Fab")
			(effects
				(font
					(size 1.27 1.27)
				)
				(justify mirror)
			)
		)
		(duplicate_pad_numbers_are_jumpers no)
		(fp_line
			(start 0.7874 -0.4064)
			(end -0.7874 -0.4064)
			(stroke
				(width 0.1524)
				(type default)
			)
			(layer "B.SilkS")
		)
		(fp_line
			(start -0.7874 -0.4064)
			(end -0.7874 0.4064)
			(stroke
				(width 0.1524)
				(type default)
			)
			(layer "B.SilkS")
		)
		(fp_line
			(start 0.7874 0.4064)
			(end 0.7874 -0.4064)
			(stroke
				(width 0.1524)
				(type default)
			)
			(layer "B.SilkS")
		)
		(fp_line
			(start -0.7874 0.4064)
			(end 0.7874 0.4064)
			(stroke
				(width 0.1524)
				(type default)
			)
			(layer "B.SilkS")
		)
		(fp_line
			(start 0.67945 -0.305054)
			(end 0.12065 -0.305054)
			(stroke
				(width 0.1)
				(type default)
			)
			(layer "B.Fab")
		)
		(fp_line
			(start 0.12065 -0.305054)
			(end 0.12065 -0.2794)
			(stroke
				(width 0.1)
				(type default)
			)
			(layer "B.Fab")
		)
		(fp_line
			(start -0.12065 -0.3048)
			(end -0.67945 -0.3048)
			(stroke
				(width 0.1)
				(type default)
			)
			(layer "B.Fab")
		)
		(fp_line
			(start -0.67945 -0.3048)
			(end -0.67945 0.3048)
			(stroke
				(width 0.1)
				(type default)
			)
			(layer "B.Fab")
		)
		(fp_line
			(start 0.12065 -0.2794)
			(end -0.12065 -0.2794)
			(stroke
				(width 0.1)
				(type default)
			)
			(layer "B.Fab")
		)
		(fp_line
			(start -0.12065 -0.2794)
			(end -0.12065 -0.3048)
			(stroke
				(width 0.1)
				(type default)
			)
			(layer "B.Fab")
		)
		(fp_line
			(start 0.12065 0.2794)
			(end 0.12065 0.3048)
			(stroke
				(width 0.1)
				(type default)
			)
			(layer "B.Fab")
		)
		(fp_line
			(start -0.120396 0.2794)
			(end 0.12065 0.2794)
			(stroke
				(width 0.1)
				(type default)
			)
			(layer "B.Fab")
		)
		(fp_line
			(start 0.67945 0.3048)
			(end 0.67945 -0.305054)
			(stroke
				(width 0.1)
				(type default)
			)
			(layer "B.Fab")
		)
		(fp_line
			(start 0.12065 0.3048)
			(end 0.67945 0.3048)
			(stroke
				(width 0.1)
				(type default)
			)
			(layer "B.Fab")
		)
		(fp_line
			(start -0.120396 0.3048)
			(end -0.120396 0.2794)
			(stroke
				(width 0.1)
				(type default)
			)
			(layer "B.Fab")
		)
		(fp_line
			(start -0.67945 0.3048)
			(end -0.120396 0.3048)
			(stroke
				(width 0.1)
				(type default)
			)
			(layer "B.Fab")
		)
		(pad "1" smd circle
			(at 0.40005 0 270)
			(size 0 0)
			(layers "B.Cu" "B.Mask" "B.Paste")
			(net "P3V3")
		)
		(pad "2" smd circle
			(at -0.40005 0 270)
			(size 0 0)
			(layers "B.Cu" "B.Mask" "B.Paste")
			(net "PVCCIN_CPU0_PVCC")
		)
	)
	(footprint ""
		(layer "B.Cu")
		(at 45.857922 -357.91521 180)
		(property "Reference" "PC1679"
			(at 0 0 0)
			(layer "B.SilkS")
			(hide yes)
			(effects
				(font
					(size 1.27 1.27)
				)
				(justify mirror)
			)
		)
		(property "Value" ""
			(at 0 0 0)
			(layer "B.Fab")
			(effects
				(font
					(size 1.27 1.27)
				)
				(justify mirror)
			)
		)
		(duplicate_pad_numbers_are_jumpers no)
		(fp_line
			(start 1.524 0.762)
			(end 1.524 -0.762)
			(stroke
				(width 0.1524)
				(type default)
			)
			(layer "B.SilkS")
		)
		(fp_line
			(start 1.524 -0.762)
			(end -1.524 -0.762)
			(stroke
				(width 0.1524)
				(type default)
			)
			(layer "B.SilkS")
		)
		(fp_line
			(start -1.524 0.762)
			(end 1.524 0.762)
			(stroke
				(width 0.1524)
				(type default)
			)
			(layer "B.SilkS")
		)
		(fp_line
			(start -1.524 -0.762)
			(end -1.524 0.762)
			(stroke
				(width 0.1524)
				(type default)
			)
			(layer "B.SilkS")
		)
		(fp_line
			(start 1.1049 0.724916)
			(end -1.1049 0.724916)
			(stroke
				(width 0.1)
				(type default)
			)
			(layer "B.Fab")
		)
		(fp_line
			(start 1.1049 -0.724916)
			(end 1.1049 0.724916)
			(stroke
				(width 0.1)
				(type default)
			)
			(layer "B.Fab")
		)
		(fp_line
			(start -1.1049 0.724916)
			(end -1.1049 -0.724916)
			(stroke
				(width 0.1)
				(type default)
			)
			(layer "B.Fab")
		)
		(fp_line
			(start -1.1049 -0.724916)
			(end 1.1049 -0.724916)
			(stroke
				(width 0.1)
				(type default)
			)
			(layer "B.Fab")
		)
		(pad "1" smd rect
			(at 0.889 0 180)
			(size 1.016 1.27)
			(layers "B.Cu" "B.Mask" "B.Paste")
			(net "SW_P12V_PVCCFA_EHV_FIVRA_CPU1_L")
		)
		(pad "2" smd rect
			(at -0.889 0 180)
			(size 1.016 1.27)
			(layers "B.Cu" "B.Mask" "B.Paste")
			(net "GND")
		)
	)
	(footprint ""
		(layer "B.Cu")
		(at 432.325018 -177.15611 90)
		(property "Reference" "R1445"
			(at 0 0 90)
			(layer "B.SilkS")
			(hide yes)
			(effects
				(font
					(size 1.27 1.27)
				)
				(justify mirror)
			)
		)
		(property "Value" ""
			(at 0 0 90)
			(layer "B.Fab")
			(effects
				(font
					(size 1.27 1.27)
				)
				(justify mirror)
			)
		)
		(duplicate_pad_numbers_are_jumpers no)
		(fp_line
			(start 0.7874 -0.4064)
			(end -0.7874 -0.4064)
			(stroke
				(width 0.1524)
				(type default)
			)
			(layer "B.SilkS")
		)
		(fp_line
			(start -0.7874 -0.4064)
			(end -0.7874 0.4064)
			(stroke
				(width 0.1524)
				(type default)
			)
			(layer "B.SilkS")
		)
		(fp_line
			(start 0.7874 0.4064)
			(end 0.7874 -0.4064)
			(stroke
				(width 0.1524)
				(type default)
			)
			(layer "B.SilkS")
		)
		(fp_line
			(start -0.7874 0.4064)
			(end 0.7874 0.4064)
			(stroke
				(width 0.1524)
				(type default)
			)
			(layer "B.SilkS")
		)
		(fp_line
			(start 0.67945 -0.305054)
			(end 0.12065 -0.305054)
			(stroke
				(width 0.1)
				(type default)
			)
			(layer "B.Fab")
		)
		(fp_line
			(start 0.12065 -0.305054)
			(end 0.12065 -0.2794)
			(stroke
				(width 0.1)
				(type default)
			)
			(layer "B.Fab")
		)
		(fp_line
			(start -0.12065 -0.3048)
			(end -0.67945 -0.3048)
			(stroke
				(width 0.1)
				(type default)
			)
			(layer "B.Fab")
		)
		(fp_line
			(start -0.67945 -0.3048)
			(end -0.67945 0.3048)
			(stroke
				(width 0.1)
				(type default)
			)
			(layer "B.Fab")
		)
		(fp_line
			(start 0.12065 -0.2794)
			(end -0.12065 -0.2794)
			(stroke
				(width 0.1)
				(type default)
			)
			(layer "B.Fab")
		)
		(fp_line
			(start -0.12065 -0.2794)
			(end -0.12065 -0.3048)
			(stroke
				(width 0.1)
				(type default)
			)
			(layer "B.Fab")
		)
		(fp_line
			(start 0.12065 0.2794)
			(end 0.12065 0.3048)
			(stroke
				(width 0.1)
				(type default)
			)
			(layer "B.Fab")
		)
		(fp_line
			(start -0.120396 0.2794)
			(end 0.12065 0.2794)
			(stroke
				(width 0.1)
				(type default)
			)
			(layer "B.Fab")
		)
		(fp_line
			(start 0.67945 0.3048)
			(end 0.67945 -0.305054)
			(stroke
				(width 0.1)
				(type default)
			)
			(layer "B.Fab")
		)
		(fp_line
			(start 0.12065 0.3048)
			(end 0.67945 0.3048)
			(stroke
				(width 0.1)
				(type default)
			)
			(layer "B.Fab")
		)
		(fp_line
			(start -0.120396 0.3048)
			(end -0.120396 0.2794)
			(stroke
				(width 0.1)
				(type default)
			)
			(layer "B.Fab")
		)
		(fp_line
			(start -0.67945 0.3048)
			(end -0.120396 0.3048)
			(stroke
				(width 0.1)
				(type default)
			)
			(layer "B.Fab")
		)
		(pad "1" smd circle
			(at 0.40005 0 270)
			(size 0 0)
			(layers "B.Cu" "B.Mask" "B.Paste")
			(net "FM_PVNN_MAIN_CPU0_EN")
		)
		(pad "2" smd circle
			(at -0.40005 0 270)
			(size 0 0)
			(layers "B.Cu" "B.Mask" "B.Paste")
			(net "GND")
		)
	)
)
